# T6G (Grand Teton) — schematic netlist excerpt (pin names and nets, part order shuffled) for the footprints in the layout excerpt that follows; sources: Cadence DE-HDL packaged netlist, KiCad conversion of 04192023_DAF0TMB3IC0_F0TG_MB_C_brd_V02_OCP.brd

R169  Q_RES  33 5% CHIP  pkg 0402LF  page 80 : A = FM_I3C_CPU1_MUX0_OE_R_N ; B = FM_I3C_CPU1_MUX0_OE_N
R551  Q_RES  4.7K 5% CHIP  pkg 0402LF  page 55 : A = CPU1_SPD_HOST_CTRL_N ; B = PVDD18_S5_P1
C704  Q_CAP_DIFFBUS  DIFF BUS_0.22UF 6.3V 20% X6S  pkg C0201  page 67 : \1\ = P5E_CPU1_G1_TX_C_DN<2> ; \2\ = P5E_CPU1_G1_TX_DN<2>

(kicad_pcb
	(version 20260206)
	(generator "pcbnew")
	(generator_version "10.0")
	(general
		(thickness 1.6)
		(legacy_teardrops no)
	)
	(paper "A4")
	(title_block
		(title "04192023_DAF0TMB3IC0_F0TG_MB_C_brd_V02_OCP.brd")
		(comment 1 "Grand Teton / footprints 2521-2523 of 8354")
	)
	(layers
		(0 "F.Cu" signal "TOP")
		(4 "In1.Cu" signal "GND")
		(6 "In2.Cu" signal "IN1")
		(8 "In3.Cu" signal "GND1")
		(10 "In4.Cu" signal "IN2")
		(12 "In5.Cu" signal "GND2")
		(14 "In6.Cu" signal "IN3")
		(16 "In7.Cu" signal "GND3")
		(18 "In8.Cu" signal "VCC")
		(20 "In9.Cu" signal "VCC1")
		(22 "In10.Cu" signal "GND4")
		(24 "In11.Cu" signal "IN4")
		(26 "In12.Cu" signal "GND5")
		(28 "In13.Cu" signal "IN5")
		(30 "In14.Cu" signal "GND6")
		(32 "In15.Cu" signal "IN6")
		(34 "In16.Cu" signal "GND7")
		(2 "B.Cu" signal "BOTTOM")
		(9 "F.Adhes" user "F.Adhesive")
		(11 "B.Adhes" user "B.Adhesive")
		(13 "F.Paste" user "Package Geometry/Pastemask Top")
		(15 "B.Paste" user "Package Geometry/Pastemask Bottom")
		(5 "F.SilkS" user "Ref Des/Silkscreen Top")
		(7 "B.SilkS" user "Ref Des/Silkscreen Bottom")
		(1 "F.Mask" user "Board Geometry/Soldermask Top")
		(3 "B.Mask" user "Board Geometry/Soldermask Bottom")
		(17 "Dwgs.User" user "User.Drawings")
		(19 "Cmts.User" user "User.Comments")
		(21 "Eco1.User" user "User.Eco1")
		(23 "Eco2.User" user "User.Eco2")
		(25 "Edge.Cuts" user "Board Geometry/Outline")
		(27 "Margin" user)
		(31 "F.CrtYd" user "Package Geometry/Place Bound Top")
		(29 "B.CrtYd" user "Package Geometry/Place Bound Bottom")
		(35 "F.Fab" user "Ref Des/Assembly Top")
		(33 "B.Fab" user "Ref Des/Assembly Bottom")
	)
	(footprint ""
		(layer "F.Cu")
		(at 144.386554 -321.695572 -90)
		(property "Reference" "R551"
			(at 0 0 270)
			(layer "F.SilkS")
			(hide yes)
			(effects
				(font
					(size 1.27 1.27)
				)
			)
		)
		(property "Value" ""
			(at 0 0 270)
			(layer "F.Fab")
			(effects
				(font
					(size 1.27 1.27)
				)
			)
		)
		(duplicate_pad_numbers_are_jumpers no)
		(fp_line
			(start -0.7874 0.4064)
			(end -0.7874 -0.4064)
			(stroke
				(width 0.1524)
				(type default)
			)
			(layer "F.SilkS")
		)
		(fp_line
			(start 0.7874 0.4064)
			(end -0.7874 0.4064)
			(stroke
				(width 0.1524)
				(type default)
			)
			(layer "F.SilkS")
		)
		(fp_line
			(start -0.7874 -0.4064)
			(end 0.7874 -0.4064)
			(stroke
				(width 0.1524)
				(type default)
			)
			(layer "F.SilkS")
		)
		(fp_line
			(start 0.7874 -0.4064)
			(end 0.7874 0.4064)
			(stroke
				(width 0.1524)
				(type default)
			)
			(layer "F.SilkS")
		)
		(fp_line
			(start -0.67945 0.3048)
			(end -0.67945 -0.305054)
			(stroke
				(width 0.1)
				(type default)
			)
			(layer "F.Fab")
		)
		(fp_line
			(start -0.12065 0.3048)
			(end -0.67945 0.3048)
			(stroke
				(width 0.1)
				(type default)
			)
			(layer "F.Fab")
		)
		(fp_line
			(start 0.120396 0.3048)
			(end 0.120396 0.2794)
			(stroke
				(width 0.1)
				(type default)
			)
			(layer "F.Fab")
		)
		(fp_line
			(start 0.67945 0.3048)
			(end 0.120396 0.3048)
			(stroke
				(width 0.1)
				(type default)
			)
			(layer "F.Fab")
		)
		(fp_line
			(start -0.12065 0.2794)
			(end -0.12065 0.3048)
			(stroke
				(width 0.1)
				(type default)
			)
			(layer "F.Fab")
		)
		(fp_line
			(start 0.120396 0.2794)
			(end -0.12065 0.2794)
			(stroke
				(width 0.1)
				(type default)
			)
			(layer "F.Fab")
		)
		(fp_line
			(start -0.12065 -0.2794)
			(end 0.12065 -0.2794)
			(stroke
				(width 0.1)
				(type default)
			)
			(layer "F.Fab")
		)
		(fp_line
			(start 0.12065 -0.2794)
			(end 0.12065 -0.3048)
			(stroke
				(width 0.1)
				(type default)
			)
			(layer "F.Fab")
		)
		(fp_line
			(start 0.12065 -0.3048)
			(end 0.67945 -0.3048)
			(stroke
				(width 0.1)
				(type default)
			)
			(layer "F.Fab")
		)
		(fp_line
			(start 0.67945 -0.3048)
			(end 0.67945 0.3048)
			(stroke
				(width 0.1)
				(type default)
			)
			(layer "F.Fab")
		)
		(fp_line
			(start -0.67945 -0.305054)
			(end -0.12065 -0.305054)
			(stroke
				(width 0.1)
				(type default)
			)
			(layer "F.Fab")
		)
		(fp_line
			(start -0.12065 -0.305054)
			(end -0.12065 -0.2794)
			(stroke
				(width 0.1)
				(type default)
			)
			(layer "F.Fab")
		)
		(pad "1" smd circle
			(at -0.40005 0 270)
			(size 0 0)
			(layers "F.Cu" "F.Mask" "F.Paste")
			(net "CPU1_SPD_HOST_CTRL_N")
		)
		(pad "2" smd circle
			(at 0.40005 0 270)
			(size 0 0)
			(layers "F.Cu" "F.Mask" "F.Paste")
			(net "PVDD18_S5_P1")
		)
	)
	(footprint ""
		(layer "F.Cu")
		(at 52.17033 -17.623536 90)
		(property "Reference" "C704"
			(at 0 0 90)
			(layer "F.SilkS")
			(hide yes)
			(effects
				(font
					(size 1.27 1.27)
				)
			)
		)
		(property "Value" ""
			(at 0 0 90)
			(layer "F.Fab")
			(effects
				(font
					(size 1.27 1.27)
				)
			)
		)
		(duplicate_pad_numbers_are_jumpers no)
		(fp_line
			(start 0.299974 -0.150114)
			(end 0.299974 0.150114)
			(stroke
				(width 0.1)
				(type default)
			)
			(layer "F.Fab")
		)
		(fp_line
			(start -0.299974 -0.150114)
			(end 0.299974 -0.150114)
			(stroke
				(width 0.1)
				(type default)
			)
			(layer "F.Fab")
		)
		(fp_line
			(start 0.299974 0.150114)
			(end -0.299974 0.150114)
			(stroke
				(width 0.1)
				(type default)
			)
			(layer "F.Fab")
		)
		(fp_line
			(start -0.299974 0.150114)
			(end -0.299974 -0.150114)
			(stroke
				(width 0.1)
				(type default)
			)
			(layer "F.Fab")
		)
		(pad "1" smd rect
			(at -0.2667 0 90)
			(size 0.3048 0.381)
			(layers "F.Cu" "F.Mask" "F.Paste")
			(net "P5E_CPU1_G1_TX_C_DN<2>")
		)
		(pad "2" smd rect
			(at 0.2667 0 90)
			(size 0.3048 0.381)
			(layers "F.Cu" "F.Mask" "F.Paste")
			(net "P5E_CPU1_G1_TX_DN<2>")
		)
	)
	(footprint ""
		(layer "F.Cu")
		(at 171.196 -104.993948 180)
		(property "Reference" "R169"
			(at 0 0 180)
			(layer "F.SilkS")
			(hide yes)
			(effects
				(font
					(size 1.27 1.27)
				)
			)
		)
		(property "Value" ""
			(at 0 0 180)
			(layer "F.Fab")
			(effects
				(font
					(size 1.27 1.27)
				)
			)
		)
		(duplicate_pad_numbers_are_jumpers no)
		(fp_line
			(start 0.7874 0.4064)
			(end -0.7874 0.4064)
			(stroke
				(width 0.1524)
				(type default)
			)
			(layer "F.SilkS")
		)
		(fp_line
			(start 0.7874 -0.4064)
			(end 0.7874 0.4064)
			(stroke
				(width 0.1524)
				(type default)
			)
			(layer "F.SilkS")
		)
		(fp_line
			(start -0.7874 0.4064)
			(end -0.7874 -0.4064)
			(stroke
				(width 0.1524)
				(type default)
			)
			(layer "F.SilkS")
		)
		(fp_line
			(start -0.7874 -0.4064)
			(end 0.7874 -0.4064)
			(stroke
				(width 0.1524)
				(type default)
			)
			(layer "F.SilkS")
		)
		(fp_line
			(start 0.67945 0.3048)
			(end 0.120396 0.3048)
			(stroke
				(width 0.1)
				(type default)
			)
			(layer "F.Fab")
		)
		(fp_line
			(start 0.67945 -0.3048)
			(end 0.67945 0.3048)
			(stroke
				(width 0.1)
				(type default)
			)
			(layer "F.Fab")
		)
		(fp_line
			(start 0.12065 -0.2794)
			(end 0.12065 -0.3048)
			(stroke
				(width 0.1)
				(type default)
			)
			(layer "F.Fab")
		)
		(fp_line
			(start 0.12065 -0.3048)
			(end 0.67945 -0.3048)
			(stroke
				(width 0.1)
				(type default)
			)
			(layer "F.Fab")
		)
		(fp_line
			(start 0.120396 0.3048)
			(end 0.120396 0.2794)
			(stroke
				(width 0.1)
				(type default)
			)
			(layer "F.Fab")
		)
		(fp_line
			(start 0.120396 0.2794)
			(end -0.12065 0.2794)
			(stroke
				(width 0.1)
				(type default)
			)
			(layer "F.Fab")
		)
		(fp_line
			(start -0.12065 0.3048)
			(end -0.67945 0.3048)
			(stroke
				(width 0.1)
				(type default)
			)
			(layer "F.Fab")
		)
		(fp_line
			(start -0.12065 0.2794)
			(end -0.12065 0.3048)
			(stroke
				(width 0.1)
				(type default)
			)
			(layer "F.Fab")
		)
		(fp_line
			(start -0.12065 -0.2794)
			(end 0.12065 -0.2794)
			(stroke
				(width 0.1)
				(type default)
			)
			(layer "F.Fab")
		)
		(fp_line
			(start -0.12065 -0.305054)
			(end -0.12065 -0.2794)
			(stroke
				(width 0.1)
				(type default)
			)
			(layer "F.Fab")
		)
		(fp_line
			(start -0.67945 0.3048)
			(end -0.67945 -0.305054)
			(stroke
				(width 0.1)
				(type default)
			)
			(layer "F.Fab")
		)
		(fp_line
			(start -0.67945 -0.305054)
			(end -0.12065 -0.305054)
			(stroke
				(width 0.1)
				(type default)
			)
			(layer "F.Fab")
		)
		(pad "1" smd circle
			(at -0.40005 0 180)
			(size 0 0)
			(layers "F.Cu" "F.Mask" "F.Paste")
			(net "FM_I3C_CPU1_MUX0_OE_R_N")
		)
		(pad "2" smd circle
			(at 0.40005 0 180)
			(size 0 0)
			(layers "F.Cu" "F.Mask" "F.Paste")
			(net "FM_I3C_CPU1_MUX0_OE_N")
		)
	)
)
